# T6G (Grand Teton) — schematic netlist excerpt (pin names and nets, part order shuffled) for the footprints in the layout excerpt that follows; sources: Cadence DE-HDL packaged netlist, KiCad conversion of 04192023_DAF0TMB3IC0_F0TG_MB_C_brd_V02_OCP.brd

C2628  Q_CAP  22UF 4V 20% X6S  pkg C0402  page 70 : A = PVDD11_S3_P0 ; B = GND
R990  Q_RES  0 5% EMPTY  pkg 0402LF  page 159 : A = I3C_1_SPD_DDRGL_CPU1_R_SCL ; B = I3C_SPD_DDRGL_CPU1_BYPASS_SCL

(kicad_pcb
	(version 20260206)
	(generator "pcbnew")
	(generator_version "10.0")
	(general
		(thickness 1.6)
		(legacy_teardrops no)
	)
	(paper "A4")
	(title_block
		(title "04192023_DAF0TMB3IC0_F0TG_MB_C_brd_V02_OCP.brd")
		(comment 1 "Grand Teton / footprints 6508-6509 of 8354")
	)
	(layers
		(0 "F.Cu" signal "TOP")
		(4 "In1.Cu" signal "GND")
		(6 "In2.Cu" signal "IN1")
		(8 "In3.Cu" signal "GND1")
		(10 "In4.Cu" signal "IN2")
		(12 "In5.Cu" signal "GND2")
		(14 "In6.Cu" signal "IN3")
		(16 "In7.Cu" signal "GND3")
		(18 "In8.Cu" signal "VCC")
		(20 "In9.Cu" signal "VCC1")
		(22 "In10.Cu" signal "GND4")
		(24 "In11.Cu" signal "IN4")
		(26 "In12.Cu" signal "GND5")
		(28 "In13.Cu" signal "IN5")
		(30 "In14.Cu" signal "GND6")
		(32 "In15.Cu" signal "IN6")
		(34 "In16.Cu" signal "GND7")
		(2 "B.Cu" signal "BOTTOM")
		(9 "F.Adhes" user "F.Adhesive")
		(11 "B.Adhes" user "B.Adhesive")
		(13 "F.Paste" user "Package Geometry/Pastemask Top")
		(15 "B.Paste" user "Package Geometry/Pastemask Bottom")
		(5 "F.SilkS" user "Ref Des/Silkscreen Top")
		(7 "B.SilkS" user "Ref Des/Silkscreen Bottom")
		(1 "F.Mask" user "Board Geometry/Soldermask Top")
		(3 "B.Mask" user "Board Geometry/Soldermask Bottom")
		(17 "Dwgs.User" user "User.Drawings")
		(19 "Cmts.User" user "User.Comments")
		(21 "Eco1.User" user "User.Eco1")
		(23 "Eco2.User" user "User.Eco2")
		(25 "Edge.Cuts" user "Board Geometry/Outline")
		(27 "Margin" user)
		(31 "F.CrtYd" user "Package Geometry/Place Bound Top")
		(29 "B.CrtYd" user "Package Geometry/Place Bound Bottom")
		(35 "F.Fab" user "Ref Des/Assembly Top")
		(33 "B.Fab" user "Ref Des/Assembly Bottom")
	)
	(footprint ""
		(layer "B.Cu")
		(at 373.075454 -264.35431)
		(property "Reference" "C2628"
			(at 0 0 0)
			(layer "B.SilkS")
			(hide yes)
			(effects
				(font
					(size 1.27 1.27)
				)
				(justify mirror)
			)
		)
		(property "Value" ""
			(at 0 0 0)
			(layer "B.Fab")
			(effects
				(font
					(size 1.27 1.27)
				)
				(justify mirror)
			)
		)
		(duplicate_pad_numbers_are_jumpers no)
		(fp_line
			(start -0.7874 -0.4064)
			(end -0.7874 0.4064)
			(stroke
				(width 0.1524)
				(type default)
			)
			(layer "B.SilkS")
		)
		(fp_line
			(start -0.7874 0.4064)
			(end 0.7874 0.4064)
			(stroke
				(width 0.1524)
				(type default)
			)
			(layer "B.SilkS")
		)
		(fp_line
			(start 0.7874 -0.4064)
			(end -0.7874 -0.4064)
			(stroke
				(width 0.1524)
				(type default)
			)
			(layer "B.SilkS")
		)
		(fp_line
			(start 0.7874 0.4064)
			(end 0.7874 -0.4064)
			(stroke
				(width 0.1524)
				(type default)
			)
			(layer "B.SilkS")
		)
		(fp_line
			(start -0.67945 -0.3048)
			(end -0.67945 0.3048)
			(stroke
				(width 0.1)
				(type default)
			)
			(layer "B.Fab")
		)
		(fp_line
			(start -0.67945 0.3048)
			(end -0.120396 0.3048)
			(stroke
				(width 0.1)
				(type default)
			)
			(layer "B.Fab")
		)
		(fp_line
			(start -0.12065 -0.3048)
			(end -0.67945 -0.3048)
			(stroke
				(width 0.1)
				(type default)
			)
			(layer "B.Fab")
		)
		(fp_line
			(start -0.12065 -0.2794)
			(end -0.12065 -0.3048)
			(stroke
				(width 0.1)
				(type default)
			)
			(layer "B.Fab")
		)
		(fp_line
			(start -0.120396 0.2794)
			(end 0.12065 0.2794)
			(stroke
				(width 0.1)
				(type default)
			)
			(layer "B.Fab")
		)
		(fp_line
			(start -0.120396 0.3048)
			(end -0.120396 0.2794)
			(stroke
				(width 0.1)
				(type default)
			)
			(layer "B.Fab")
		)
		(fp_line
			(start 0.12065 -0.305054)
			(end 0.12065 -0.2794)
			(stroke
				(width 0.1)
				(type default)
			)
			(layer "B.Fab")
		)
		(fp_line
			(start 0.12065 -0.2794)
			(end -0.12065 -0.2794)
			(stroke
				(width 0.1)
				(type default)
			)
			(layer "B.Fab")
		)
		(fp_line
			(start 0.12065 0.2794)
			(end 0.12065 0.3048)
			(stroke
				(width 0.1)
				(type default)
			)
			(layer "B.Fab")
		)
		(fp_line
			(start 0.12065 0.3048)
			(end 0.67945 0.3048)
			(stroke
				(width 0.1)
				(type default)
			)
			(layer "B.Fab")
		)
		(fp_line
			(start 0.67945 -0.305054)
			(end 0.12065 -0.305054)
			(stroke
				(width 0.1)
				(type default)
			)
			(layer "B.Fab")
		)
		(fp_line
			(start 0.67945 0.3048)
			(end 0.67945 -0.305054)
			(stroke
				(width 0.1)
				(type default)
			)
			(layer "B.Fab")
		)
		(pad "1" smd circle
			(at 0.40005 0 180)
			(size 0 0)
			(layers "B.Cu" "B.Mask" "B.Paste")
			(net "PVDD11_S3_P0")
		)
		(pad "2" smd circle
			(at -0.40005 0 180)
			(size 0 0)
			(layers "B.Cu" "B.Mask" "B.Paste")
			(net "GND")
		)
	)
	(footprint ""
		(layer "B.Cu")
		(at 159.615632 -193.949066 -90)
		(property "Reference" "R990"
			(at 0 0 90)
			(layer "B.SilkS")
			(hide yes)
			(effects
				(font
					(size 1.27 1.27)
				)
				(justify mirror)
			)
		)
		(property "Value" ""
			(at 0 0 90)
			(layer "B.Fab")
			(effects
				(font
					(size 1.27 1.27)
				)
				(justify mirror)
			)
		)
		(duplicate_pad_numbers_are_jumpers no)
		(fp_line
			(start -0.7874 0.4064)
			(end 0.7874 0.4064)
			(stroke
				(width 0.1524)
				(type default)
			)
			(layer "B.SilkS")
		)
		(fp_line
			(start 0.7874 0.4064)
			(end 0.7874 -0.4064)
			(stroke
				(width 0.1524)
				(type default)
			)
			(layer "B.SilkS")
		)
		(fp_line
			(start -0.7874 -0.4064)
			(end -0.7874 0.4064)
			(stroke
				(width 0.1524)
				(type default)
			)
			(layer "B.SilkS")
		)
		(fp_line
			(start 0.7874 -0.4064)
			(end -0.7874 -0.4064)
			(stroke
				(width 0.1524)
				(type default)
			)
			(layer "B.SilkS")
		)
		(fp_line
			(start -0.67945 0.3048)
			(end -0.120396 0.3048)
			(stroke
				(width 0.1)
				(type default)
			)
			(layer "B.Fab")
		)
		(fp_line
			(start -0.120396 0.3048)
			(end -0.120396 0.2794)
			(stroke
				(width 0.1)
				(type default)
			)
			(layer "B.Fab")
		)
		(fp_line
			(start 0.12065 0.3048)
			(end 0.67945 0.3048)
			(stroke
				(width 0.1)
				(type default)
			)
			(layer "B.Fab")
		)
		(fp_line
			(start 0.67945 0.3048)
			(end 0.67945 -0.305054)
			(stroke
				(width 0.1)
				(type default)
			)
			(layer "B.Fab")
		)
		(fp_line
			(start -0.120396 0.2794)
			(end 0.12065 0.2794)
			(stroke
				(width 0.1)
				(type default)
			)
			(layer "B.Fab")
		)
		(fp_line
			(start 0.12065 0.2794)
			(end 0.12065 0.3048)
			(stroke
				(width 0.1)
				(type default)
			)
			(layer "B.Fab")
		)
		(fp_line
			(start -0.12065 -0.2794)
			(end -0.12065 -0.3048)
			(stroke
				(width 0.1)
				(type default)
			)
			(layer "B.Fab")
		)
		(fp_line
			(start 0.12065 -0.2794)
			(end -0.12065 -0.2794)
			(stroke
				(width 0.1)
				(type default)
			)
			(layer "B.Fab")
		)
		(fp_line
			(start -0.67945 -0.3048)
			(end -0.67945 0.3048)
			(stroke
				(width 0.1)
				(type default)
			)
			(layer "B.Fab")
		)
		(fp_line
			(start -0.12065 -0.3048)
			(end -0.67945 -0.3048)
			(stroke
				(width 0.1)
				(type default)
			)
			(layer "B.Fab")
		)
		(fp_line
			(start 0.12065 -0.305054)
			(end 0.12065 -0.2794)
			(stroke
				(width 0.1)
				(type default)
			)
			(layer "B.Fab")
		)
		(fp_line
			(start 0.67945 -0.305054)
			(end 0.12065 -0.305054)
			(stroke
				(width 0.1)
				(type default)
			)
			(layer "B.Fab")
		)
		(pad "1" smd rect
			(at 0.40005 0 270)
			(size 0.4572 0.508)
			(layers "B.Cu" "B.Mask" "B.Paste")
			(net "I3C_1_SPD_DDRGL_CPU1_R_SCL")
		)
		(pad "2" smd rect
			(at -0.40005 0 270)
			(size 0.4572 0.508)
			(layers "B.Cu" "B.Mask" "B.Paste")
			(net "I3C_SPD_DDRGL_CPU1_BYPASS_SCL")
		)
	)
)
